FILE_TYPE = CONNECTIVITY;
{Allegro Design Entry HDL 16.6-p007 (v16-6-112F) 10/10/2012}
"PAGE_NUMBER" = 93;
0"NC";
1"PVCCIO_CPU1\g";
2"GND\g";
3"P3V3\g";
4"PVCCIO_CPU0\g";
5"GND\g";
6"PVCCIO_CPU0\g";
7"P3V3\g";
8"GND\g";
9"PVCCIO_CPU0\g";
10"GND\g";
11"H_CPU_ERR1_GTL_R_N";
12"H_CPU1_PROCHOT_G_PCH_N";
13"H_CPU0_ERR0_G_N";
14"P0V7_GTL2104_5_VREF"VOLTAGE"0.734";
15"PD_GTL2104_4_DIR";
16"FM_CPU_ERR1_LVT3_K_N";
17"H_CPU0_PROCHOT_G_PCH_N";
18"FM_CPU0_PROCHOT_LVT3_K_N";
19"P0V7_GTL2104_5_VREF";
20"PD_GTL2104_4_DIR";
21"FM_CPU_ERR0_LVT3_R_N";
22"FM_CPU1_PROCHOT_LVT3_R_N";
23"FM_CPU0_PROCHOT_LVT3_BMC_N";
24"H_CPU1_PROCHOT_G_N";
25"H_CPU0_PROCHOT_G_N";
26"FM_CPU0_PROCHOT_LVT3_R_N";
27"FM_CPU_ERR0_LVT3_N";
28"H_CPU_ERR1_PCH_N";
29"H_CPU_ERR0_PCH_N";
30"FM_CPU_ERR1_LVT3_R_N";
31"H_CPU_ERR0_GTL_N";
32"H_CPU_ERR1_GTL_N";
33"H_CPU_ERR0_GTL_R_N";
34"FM_CPU_ERR1_LVT3_BMC_N";
35"FM_CPU_ERR1_PCH_N";
36"FM_CPU1_PROCHOT_LVT3_BMC_N";
37"FM_CPU_ERR0_PCH_N";
38"FM_CPU0_PROCHOT_PCH_N";
39"FM_CPU1_PROCHOT_PCH_N";
40"FM_CPU_ERR0_LVT3_BMC_N";
41"H_CPU1_ERR1_G_N";
42"H_CPU1_ERR0_G_N";
43"H_CPU0_ERR1_G_N";
44"FM_CPU_ERR0_LVT3_N";
45"FM_CPU_ERR1_LVT3_N";
46"FM_CPU0_PROCHOT_LVT3_N";
47"FM_CPU1_PROCHOT_LVT3_N";
48"FM_CPU_ERR0_LVT3_K_N";
49"FM_CPU_ERR1_LVT3_N";
50"FM_CPU1_PROCHOT_LVT3_N";
51"FM_CPU0_PROCHOT_LVT3_N";
52"FM_CPU1_PROCHOT_LVT3_K_N";
53"H_CPU0_PROCHOT_G_R_N";
54"H_CPU1_PROCHOT_G_R_N";
%"RES"
"1","(-825,2175)","0","mstr_discrete","I102";
;
CDS_SEC"1"
CDS_LOCATION"R2T68"
VALUE"0.0"
LOCATION"R2T68"
TOLERANCE"5%"
WATTAGE"1/16W"
MATERIAL"CHIP"
PART_NUMBER"G21497-005"
PACK_TYPE"0402"
SEC"1"
SEC_TYPE"0402"
CDS_LIB"mstr_discrete";
"B"
$PN"2"54;
"A"
$PN"1"24;
%"RES"
"1","(-825,2300)","0","mstr_discrete","I103";
;
CDS_SEC"1"
CDS_LOCATION"R2T60"
LOCATION"R2T60"
TOLERANCE"5%"
MATERIAL"CHIP"
VALUE"0.0"
WATTAGE"1/16W"
PACK_TYPE"0402"
PART_NUMBER"G21497-005"
CDS_LIB"mstr_discrete"
SEC_TYPE"0402"
SEC"1";
"B"
$PN"2"53;
"A"
$PN"1"25;
%"PVCCIO_CPU1"
"1","(-2200,2800)","0","mstr_symbols","I105";
;
HDL_POWER"PVCCIO_CPU1"
CDS_LIB"mstr_symbols"
VOLTAGE"1.1V"
BODY_TYPE"PLUMBING";
"G\NAC"1;
%"RES"
"2","(-2200,2500)","0","mstr_discrete","I106";
;
CDS_SEC"1"
WATTAGE"1/16W"
PACK_TYPE"0402"
VALUE"150.0"
LOCATION"R7P28"
PART_NUMBER"G21796-009"
MATERIAL"CHIP"
TOLERANCE"1%"
SEC_TYPE"0402"
SEC"1"
CDS_LOCATION"R7P28"
CDS_LIB"mstr_discrete"
BOM_COST"PROC_SIDEBAND"
ROOM"PROC_SIDEBAND";
"A"
$PN"1"1;
"B"
$PN"2"24;
%"RES"
"2","(-1100,1900)","0","mstr_discrete","I107";
;
CDS_SEC"1"
CDS_LOCATION"R2T59"
PACK_TYPE"0402"
PART_NUMBER"G21497-005"
WATTAGE"1/16W"
TOLERANCE"5%"
VALUE"0.0"
MATERIAL"EMPTY"
LOCATION"R2T59"
SEC"1"
SEC_TYPE"0402"
CDS_LIB"mstr_discrete";
"A"
$PN"1"25;
"B"
$PN"2"17;
%"RES"
"2","(-1400,1900)","0","mstr_discrete","I108";
;
CDS_SEC"1"
CDS_LOCATION"R2T69"
LOCATION"R2T69"
WATTAGE"1/16W"
PACK_TYPE"0402"
VALUE"0.0"
PART_NUMBER"G21497-005"
MATERIAL"EMPTY"
TOLERANCE"5%"
SEC"1"
SEC_TYPE"0402"
CDS_LIB"mstr_discrete";
"A"
$PN"1"24;
"B"
$PN"2"12;
%"RES"
"2","(2025,2225)","0","mstr_discrete","I109";
;
CDS_SEC"1"
CDS_LOCATION"R2T71"
TOLERANCE"5%"
PART_NUMBER"G21497-005"
PACK_TYPE"0402"
MATERIAL"EMPTY"
WATTAGE"1/16W"
LOCATION"R2T71"
VALUE"0.0"
SEC"1"
SEC_TYPE"0402"
CDS_LIB"mstr_discrete";
"A"
$PN"1"18;
"B"
$PN"2"17;
%"RES"
"2","(2400,2225)","0","mstr_discrete","I110";
;
CDS_SEC"1"
CDS_LOCATION"R7D43"
WATTAGE"1/16W"
MATERIAL"EMPTY"
PART_NUMBER"G21497-005"
PACK_TYPE"0402"
LOCATION"R7D43"
VALUE"0.0"
TOLERANCE"5%"
SEC"1"
SEC_TYPE"0402"
CDS_LIB"mstr_discrete";
"A"
$PN"1"52;
"B"
$PN"2"12;
%"RES"
"1","(1875,3350)","0","mstr_discrete","I111";
;
CDS_SEC"1"
CDS_LOCATION"R2T65"
PART_NUMBER"G21497-005"
LOCATION"R2T65"
VALUE"0.0"
TOLERANCE"5%"
WATTAGE"1/16W"
MATERIAL"CHIP"
PACK_TYPE"0402"
SEC_TYPE"0402"
CDS_LIB"mstr_discrete"
SEC"1";
"B"
$PN"2"48;
"A"
$PN"1"21;
%"RES"
"1","(1875,3100)","0","mstr_discrete","I112";
;
CDS_SEC"1"
CDS_LOCATION"R2T66"
LOCATION"R2T66"
VALUE"0.0"
TOLERANCE"5%"
WATTAGE"1/16W"
MATERIAL"CHIP"
PART_NUMBER"G21497-005"
PACK_TYPE"0402"
SEC"1"
SEC_TYPE"0402"
CDS_LIB"mstr_discrete";
"B"
$PN"2"16;
"A"
$PN"1"30;
%"RES"
"1","(1875,2850)","0","mstr_discrete","I113";
;
CDS_SEC"1"
CDS_LOCATION"R2T67"
PACK_TYPE"0402"
PART_NUMBER"G21497-005"
MATERIAL"CHIP"
WATTAGE"1/16W"
TOLERANCE"5%"
VALUE"0.0"
LOCATION"R2T67"
SEC"1"
SEC_TYPE"0402"
CDS_LIB"mstr_discrete";
"B"
$PN"2"18;
"A"
$PN"1"26;
%"RES"
"1","(1875,2575)","0","mstr_discrete","I114";
;
CDS_SEC"1"
CDS_LOCATION"R7D41"
PART_NUMBER"G21497-005"
TOLERANCE"5%"
WATTAGE"1/16W"
VALUE"0.0"
LOCATION"R7D41"
MATERIAL"CHIP"
PACK_TYPE"0402"
SEC_TYPE"0402"
CDS_LIB"mstr_discrete"
SEC"1";
"B"
$PN"2"52;
"A"
$PN"1"22;
%"RES"
"1","(-2225,1450)","0","mstr_discrete","I119";
;
CDS_SEC"1"
CDS_LOCATION"R8F38"
PACK_TYPE"0402"
PART_NUMBER"G21497-005"
MATERIAL"CHIP"
LOCATION"R8F38"
TOLERANCE"5%"
WATTAGE"1/16W"
VALUE"0.0"
SEC"1"
SEC_TYPE"0402"
CDS_LIB"mstr_discrete";
"B"
$PN"2"40;
"A"
$PN"1"44;
%"RES"
"1","(-2225,1050)","0","mstr_discrete","I121";
;
CDS_SEC"1"
CDS_LOCATION"R2T64"
PACK_TYPE"0402"
LOCATION"R2T64"
PART_NUMBER"G21497-005"
VALUE"0.0"
WATTAGE"1/16W"
MATERIAL"CHIP"
TOLERANCE"5%"
SEC_TYPE"0402"
SEC"1"
CDS_LIB"mstr_discrete";
"B"
$PN"2"34;
"A"
$PN"1"45;
%"RES"
"1","(-2225,675)","0","mstr_discrete","I122";
;
CDS_SEC"1"
CDS_LOCATION"R1T36"
PACK_TYPE"0402"
MATERIAL"CHIP"
LOCATION"R1T36"
TOLERANCE"5%"
PART_NUMBER"G21497-005"
VALUE"0.0"
WATTAGE"1/16W"
SEC"1"
SEC_TYPE"0402"
CDS_LIB"mstr_discrete";
"B"
$PN"2"23;
"A"
$PN"1"46;
%"RES"
"1","(-2225,275)","0","mstr_discrete","I123";
;
CDS_SEC"1"
CDS_LOCATION"R1T37"
PACK_TYPE"0402"
LOCATION"R1T37"
MATERIAL"CHIP"
TOLERANCE"5%"
PART_NUMBER"G21497-005"
VALUE"0.0"
WATTAGE"1/16W"
SEC_TYPE"0402"
SEC"1"
CDS_LIB"mstr_discrete";
"B"
$PN"2"36;
"A"
$PN"1"47;
%"RES"
"2","(3700,425)","0","mstr_discrete","I127";
;
CDS_SEC"1"
PART_NUMBER"G21796-026"
LOCATION"R2T50"
VALUE"1.00K"
WATTAGE"1/16W"
MATERIAL"CHIP"
PACK_TYPE"0402"
TOLERANCE"1%"
ROOM"PROC_SIDEBAND"
CDS_LOCATION"R2T50"
SEC"1"
SEC_TYPE"0402"
BOM_COST"PROC"
CDS_LIB"mstr_discrete";
"A"
$PN"1"15;
"B"
$PN"2"2;
%"GND"
"1","(3700,225)","0","mstr_symbols","I128";
;
HDL_POWER"GND"
CDS_LIB"mstr_symbols"
VOLTAGE"0"
BODY_TYPE"PLUMBING"
SIZE"1B";
"A\NAC"2;
%"RES"
"1","(-2750,3200)","0","mstr_discrete","I13";
;
CDS_SEC"1"
PART_NUMBER"G21497-005"
LOCATION"R2T27"
TOLERANCE"5%"
PACK_TYPE"0402"
VALUE"0.0"
MATERIAL"CHIP"
WATTAGE"1/16W"
SEC"1"
SEC_TYPE"0402"
CDS_LIB"mstr_discrete"
BOM_COST"PROC"
CDS_LOCATION"R2T27"
ROOM"PROC_SIDEBAND";
"B"
$PN"2"11;
"A"
$PN"1"41;
%"RES"
"1","(-2225,1250)","0","mstr_discrete","I131";
;
CDS_SEC"1"
CDS_LOCATION"R8F37"
PACK_TYPE"0402"
LOCATION"R8F37"
TOLERANCE"5%"
PART_NUMBER"G21497-005"
VALUE"0.0"
WATTAGE"1/16W"
MATERIAL"EMPTY"
SEC"1"
SEC_TYPE"0402"
CDS_LIB"mstr_discrete";
"B"
$PN"2"37;
"A"
$PN"1"44;
%"RES"
"1","(-2225,850)","0","mstr_discrete","I133";
;
CDS_SEC"1"
CDS_LOCATION"R2T63"
LOCATION"R2T63"
MATERIAL"EMPTY"
TOLERANCE"5%"
PART_NUMBER"G21497-005"
VALUE"0.0"
WATTAGE"1/16W"
PACK_TYPE"0402"
SEC"1"
SEC_TYPE"0402"
CDS_LIB"mstr_discrete";
"B"
$PN"2"35;
"A"
$PN"1"45;
%"RES"
"1","(-2225,475)","0","mstr_discrete","I135";
;
CDS_SEC"1"
CDS_LOCATION"R1T35"
PACK_TYPE"0402"
LOCATION"R1T35"
PART_NUMBER"G21497-005"
MATERIAL"EMPTY"
TOLERANCE"5%"
VALUE"0.0"
WATTAGE"1/16W"
SEC"1"
SEC_TYPE"0402"
CDS_LIB"mstr_discrete";
"B"
$PN"2"38;
"A"
$PN"1"46;
%"RES"
"1","(-2225,75)","0","mstr_discrete","I137";
;
CDS_SEC"1"
CDS_LOCATION"R1T38"
PACK_TYPE"0402"
LOCATION"R1T38"
MATERIAL"EMPTY"
TOLERANCE"5%"
PART_NUMBER"G21497-005"
VALUE"0.0"
WATTAGE"1/16W"
SEC"1"
SEC_TYPE"0402"
CDS_LIB"mstr_discrete";
"B"
$PN"2"39;
"A"
$PN"1"47;
%"RES"
"2","(-2475,2525)","0","mstr_discrete","I143";
;
LOCATION"R2T72"
VALUE"150.0"
TOLERANCE"1%"
PART_NUMBER"G21796-009"
WATTAGE"1/16W"
MATERIAL"CHIP"
PACK_TYPE"0402"
CDS_LOCATION"R2T72"
CDS_SEC"1"
SEC_TYPE"0402"
SEC"1"
CDS_LIB"mstr_discrete"
BOM_COST"PROC_SIDEBAND"
ROOM"PROC_SIDEBAND";
"A"
$PN"1"9;
"B"
$PN"2"25;
%"RES"
"2","(-1900,2500)","0","mstr_discrete","I144";
;
PART_NUMBER"G21796-009"
WATTAGE"1/16W"
LOCATION"R2T73"
TOLERANCE"1%"
MATERIAL"CHIP"
PACK_TYPE"0402"
VALUE"150.0"
CDS_LOCATION"R2T73"
CDS_SEC"1"
SEC"1"
SEC_TYPE"0402"
BOM_COST"PROC_SIDEBAND"
CDS_LIB"mstr_discrete"
ROOM"PROC_SIDEBAND";
"A"
$PN"1"1;
"B"
$PN"2"24;
%"P3V3"
"1","(2300,1300)","0","mstr_symbols","I145";
;
SIZE"1B"
BODY_TYPE"PLUMBING"
VOLTAGE"3.3V"
CDS_LIB"mstr_symbols"
HDL_POWER"P3V3";
"G\NAC"3;
%"PVCCIO_CPU0"
"1","(1750,1300)","0","mstr_symbols","I146";
;
HDL_POWER"PVCCIO_CPU0"
BODY_TYPE"PLUMBING"
VOLTAGE"1.1V"
CDS_LIB"mstr_symbols";
"G\NAC"4;
%"RES"
"2","(1750,1100)","0","mstr_discrete","I147";
;
LOCATION"R2W2"
WATTAGE"1/16W"
TOLERANCE"1%"
PART_NUMBER"G21796-047"
MATERIAL"EMPTY"
VALUE"49.9"
PACK_TYPE"0402"
CDS_SEC"1"
SEC_TYPE"0402"
SEC"1"
ROOM"SB"
CDS_LIB"mstr_discrete"
CDS_LOCATION"R2W2";
"A"
$PN"1"4;
"B"
$PN"2"14;
%"374R2F-1-GP"
"1","(2300,1075)","0","w_hdl","I148";
;
CDS_SEC"1"
$SEC"1"
CDS_LOCATION"R2T36"
ATTRIBUTE"374 OHM"
TOLERANCE"1%"
RATED"1/16W"
LOCATION"R2T36"
PACK_SIZE"0402"
VALUE"374R2F-1-GP"
CDS_LMAN_SYM_OUTLINE"-50,75,50,-75"
CDS_LIB"w_hdl"
PART_NUMBER"64.37405.6DL"
PACK_TYPE"SMD-RG";
"2"
$PN"2"14;
"1"
$PN"1"3;
%"RES"
"1","(-2750,3425)","0","mstr_discrete","I15";
;
CDS_SEC"1"
PART_NUMBER"G21497-005"
LOCATION"R2T32"
WATTAGE"1/16W"
TOLERANCE"5%"
MATERIAL"CHIP"
VALUE"0.0"
PACK_TYPE"0402"
SEC_TYPE"0402"
SEC"1"
CDS_LIB"mstr_discrete"
BOM_COST"PROC"
CDS_LOCATION"R2T32"
ROOM"PROC_SIDEBAND";
"B"
$PN"2"11;
"A"
$PN"1"43;
%"RES"
"1","(-2750,3725)","0","mstr_discrete","I16";
;
CDS_SEC"1"
MATERIAL"CHIP"
VALUE"0.0"
TOLERANCE"5%"
LOCATION"R2T20"
WATTAGE"1/16W"
PACK_TYPE"0402"
PART_NUMBER"G21497-005"
SEC_TYPE"0402"
SEC"1"
BOM_COST"PROC"
CDS_LIB"mstr_discrete"
ROOM"PROC_SIDEBAND"
CDS_LOCATION"R2T20";
"B"
$PN"2"33;
"A"
$PN"1"42;
%"RES"
"1","(-2750,3975)","0","mstr_discrete","I23";
;
CDS_SEC"1"
PACK_TYPE"0402"
WATTAGE"1/16W"
LOCATION"R2T17"
MATERIAL"CHIP"
VALUE"0.0"
TOLERANCE"5%"
PART_NUMBER"G21497-005"
SEC_TYPE"0402"
SEC"1"
CDS_LIB"mstr_discrete"
BOM_COST"PROC"
ROOM"PROC_SIDEBAND"
CDS_LOCATION"R2T17";
"B"
$PN"2"33;
"A"
$PN"1"13;
%"GND"
"1","(-200,2825)","0","mstr_symbols","I29";
;
HDL_POWER"GND"
VOLTAGE"0"
CDS_LIB"mstr_symbols"
SIZE"1B"
BODY_TYPE"PLUMBING";
"A\NAC"5;
%"GTL2014"
"1","(425,3350)","2","mstr_digital","I30";
;
CDS_SEC"1"
LOCATION"U2T4"
MATERIAL"IC"
PART_NUMBER"D66151-001"
PACK_TYPE"SM"
ROOM"PROC_SIDEBAND"
CDS_LOCATION"U2T4"
SEC"1"
SEC_TYPE"SM"
CDS_LIB"mstr_digital"
BOM_COST"PROC";
"A0"
$PN"13"22;
"A1"
$PN"12"26;
"A3"
$PN"9"21;
"A2"
$PN"10"30;
"B2"
$PN"5"32;
"B3"
$PN"6"31;
"B0"
$PN"2"54;
"B1"
$PN"3"53;
"GND<1>"
$PN"8"5;
"GND<2>"
$PN"11"5;
"GND<0>"
$PN"7"5;
"VCC"
$PN"14"7;
"VREF"
$PN"4"19;
"DIR"
$PN"1"20;
%"RES"
"1","(2950,2850)","0","mstr_discrete","I39";
;
CDS_SEC"1"
VALUE"33.2"
PACK_TYPE"0402"
LOCATION"R2T38"
TOLERANCE"1%"
MATERIAL"CHIP"
WATTAGE"1/16W"
PART_NUMBER"G21796-074"
SEC"1"
SEC_TYPE"0402"
CDS_LIB"mstr_discrete"
BOM_COST"PROC"
CDS_LOCATION"R2T38"
ROOM"PROC_SIDEBAND";
"B"
$PN"2"51;
"A"
$PN"1"18;
%"RES"
"1","(2950,3100)","0","mstr_discrete","I40";
;
CDS_SEC"1"
WATTAGE"1/16W"
PACK_TYPE"0402"
LOCATION"R2T33"
TOLERANCE"1%"
VALUE"33.2"
PART_NUMBER"G21796-074"
MATERIAL"CHIP"
SEC"1"
SEC_TYPE"0402"
BOM_COST"PROC"
CDS_LIB"mstr_discrete"
CDS_LOCATION"R2T33"
ROOM"PROC_SIDEBAND";
"B"
$PN"2"49;
"A"
$PN"1"16;
%"RES"
"1","(2950,3350)","0","mstr_discrete","I42";
;
CDS_SEC"1"
LOCATION"R2T30"
PACK_TYPE"0402"
PART_NUMBER"G21796-074"
TOLERANCE"1%"
MATERIAL"CHIP"
WATTAGE"1/16W"
VALUE"33.2"
SEC_TYPE"0402"
CDS_LIB"mstr_discrete"
BOM_COST"PROC"
CDS_LOCATION"R2T30"
SEC"1"
ROOM"PROC_SIDEBAND";
"B"
$PN"2"27;
"A"
$PN"1"48;
%"RES"
"1","(2950,2575)","0","mstr_discrete","I62";
;
CDS_SEC"1"
VALUE"33.2"
LOCATION"R7D24"
WATTAGE"1/16W"
TOLERANCE"1%"
PACK_TYPE"0402"
PART_NUMBER"G21796-074"
MATERIAL"CHIP"
SEC_TYPE"0402"
CDS_LIB"mstr_discrete"
BOM_COST"PROC"
CDS_LOCATION"R7D24"
SEC"1"
ROOM"PROC_SIDEBAND";
"B"
$PN"2"50;
"A"
$PN"1"52;
%"RES"
"2","(-2325,4050)","0","mstr_discrete","I63";
;
CDS_SEC"1"
LOCATION"R2T19"
TOLERANCE"1%"
PACK_TYPE"0402"
PART_NUMBER"G21796-004"
MATERIAL"CHIP"
WATTAGE"1/16W"
VALUE"200.0"
CDS_LOCATION"R2T19"
SEC"1"
SEC_TYPE"0402"
ROOM"PROC_SIDEBAND"
BOM_COST"PROC"
CDS_LIB"mstr_discrete";
"A"
$PN"1"6;
"B"
$PN"2"33;
%"PVCCIO_CPU0"
"1","(-2325,4300)","0","mstr_symbols","I64";
;
HDL_POWER"PVCCIO_CPU0"
VOLTAGE"1.1V"
CDS_LIB"mstr_symbols"
BODY_TYPE"PLUMBING";
"G\NAC"6;
%"RES"
"1","(-925,3825)","0","mstr_discrete","I67";
;
CDS_SEC"1"
LOCATION"R2T16"
TOLERANCE"1.0%"
PACK_TYPE"0402"
MATERIAL"CHIP"
VALUE"75"
WATTAGE"1/16W"
PART_NUMBER"G21796-267"
ROOM"PROC_SIDEBAND"
CDS_LOCATION"R2T16"
SEC"1"
SEC_TYPE"0402"
CDS_LIB"mstr_discrete";
"B"
$PN"2"31;
"A"
$PN"1"33;
%"RES"
"1","(-925,3300)","0","mstr_discrete","I68";
;
CDS_SEC"1"
LOCATION"R2T31"
VALUE"75"
TOLERANCE"1.0%"
MATERIAL"CHIP"
WATTAGE"1/16W"
PART_NUMBER"G21796-267"
PACK_TYPE"0402"
SEC"1"
CDS_LOCATION"R2T31"
SEC_TYPE"0402"
ROOM"PROC_SIDEBAND"
CDS_LIB"mstr_discrete";
"B"
$PN"2"32;
"A"
$PN"1"11;
%"P3V3"
"1","(1000,4150)","0","mstr_symbols","I70";
;
HDL_POWER"P3V3"
CDS_LIB"mstr_symbols"
VOLTAGE"3.3V"
BODY_TYPE"PLUMBING"
SIZE"1B";
"G\NAC"7;
%"CAP_A"
"1","(1150,3875)","0","dev_discrete","I72";
;
MATERIAL"X6S"
VOLTAGE"6.3V"
PACK_TYPE"0402V"
TOLERANCE"10%"
VALUE"1.0UF"
PART_NUMBER"D97712-004"
LOCATION"C2T33"
SEC"1"
SEC_TYPE"0402V"
CDS_SEC"1"
CDS_LIB"dev_discrete"
BOM_COST"PROC"
CDS_LOCATION"C2T33"
ROOM"PROC_SIDEBAND";
"B"
$PN"2"8;
"A"
$PN"1"7;
%"GND"
"1","(1150,3675)","0","mstr_symbols","I73";
;
HDL_POWER"GND"
SIZE"1B"
VOLTAGE"0"
CDS_LIB"mstr_symbols"
BODY_TYPE"PLUMBING";
"A\NAC"8;
%"PVCCIO_CPU0"
"1","(-2750,2800)","0","mstr_symbols","I78";
;
HDL_POWER"PVCCIO_CPU0"
CDS_LIB"mstr_symbols"
BODY_TYPE"PLUMBING"
VOLTAGE"1.1V";
"G\NAC"9;
%"RES"
"2","(-2750,2525)","0","mstr_discrete","I79";
;
CDS_SEC"1"
PART_NUMBER"G21796-009"
VALUE"150.0"
LOCATION"R4R3"
TOLERANCE"1%"
WATTAGE"1/16W"
MATERIAL"CHIP"
PACK_TYPE"0402"
SEC_TYPE"0402"
SEC"1"
CDS_LOCATION"R4R3"
BOM_COST"PROC_SIDEBAND"
CDS_LIB"mstr_discrete"
ROOM"PROC_SIDEBAND";
"A"
$PN"1"9;
"B"
$PN"2"25;
%"RES"
"2","(-2025,4050)","0","mstr_discrete","I87";
;
CDS_SEC"1"
LOCATION"R2T26"
VALUE"200.0"
TOLERANCE"1%"
PACK_TYPE"0402"
PART_NUMBER"G21796-004"
WATTAGE"1/16W"
MATERIAL"CHIP"
CDS_LOCATION"R2T26"
SEC"1"
SEC_TYPE"0402"
CDS_LIB"mstr_discrete"
BOM_COST"PROC"
ROOM"PROC_SIDEBAND";
"A"
$PN"1"6;
"B"
$PN"2"11;
%"RES"
"2","(-1375,4125)","0","mstr_discrete","I88";
;
CDS_SEC"1"
CDS_LOCATION"R2T57"
WATTAGE"1/16W"
TOLERANCE"5%"
VALUE"0.0"
LOCATION"R2T57"
PACK_TYPE"0402"
PART_NUMBER"G21497-005"
MATERIAL"EMPTY"
SEC"1"
SEC_TYPE"0402"
CDS_LIB"mstr_discrete";
"A"
$PN"1"29;
"B"
$PN"2"33;
%"RES"
"2","(-1100,4125)","0","mstr_discrete","I89";
;
CDS_SEC"1"
CDS_LOCATION"R2T61"
WATTAGE"1/16W"
TOLERANCE"5%"
VALUE"0.0"
LOCATION"R2T61"
PACK_TYPE"0402"
PART_NUMBER"G21497-005"
MATERIAL"EMPTY"
SEC"1"
SEC_TYPE"0402"
CDS_LIB"mstr_discrete";
"A"
$PN"1"28;
"B"
$PN"2"11;
%"RES"
"2","(2025,3850)","0","mstr_discrete","I93";
;
CDS_SEC"1"
CDS_LOCATION"R2T62"
PACK_TYPE"0402"
PART_NUMBER"G21497-005"
MATERIAL"EMPTY"
WATTAGE"1/16W"
TOLERANCE"5%"
VALUE"0.0"
LOCATION"R2T62"
SEC"1"
SEC_TYPE"0402"
CDS_LIB"mstr_discrete";
"A"
$PN"1"28;
"B"
$PN"2"16;
%"RES"
"2","(2400,3850)","0","mstr_discrete","I94";
;
CDS_SEC"1"
CDS_LOCATION"R2T58"
PACK_TYPE"0402"
PART_NUMBER"G21497-005"
WATTAGE"1/16W"
LOCATION"R2T58"
MATERIAL"EMPTY"
VALUE"0.0"
TOLERANCE"5%"
SEC"1"
SEC_TYPE"0402"
CDS_LIB"mstr_discrete";
"A"
$PN"1"29;
"B"
$PN"2"48;
%"CAP_A"
"1","(1950,600)","0","dev_discrete","I95";
;
TOLERANCE"10%"
VOLTAGE"16V"
VALUE"0.1UF"
PART_NUMBER"A36096-030"
PACK_TYPE"0402V"
MATERIAL"X7R"
LOCATION"C2T32"
ROOM"PROC_SIDEBAND"
CDS_LIB"dev_discrete"
BOM_COST"PROC"
CDS_LOCATION"C2T32"
SEC"1"
SEC_TYPE"0402V"
CDS_SEC"1";
"B"
$PN"2"10;
"A"
$PN"1"14;
%"RES"
"2","(2300,600)","0","mstr_discrete","I98";
;
CDS_SEC"1"
PART_NUMBER"G21796-017"
PACK_TYPE"0402"
MATERIAL"CHIP"
WATTAGE"1/16W"
TOLERANCE"1%"
VALUE"100.0"
LOCATION"R2T39"
CDS_LIB"mstr_discrete"
BOM_COST"PROC"
CDS_LOCATION"R2T39"
SEC_TYPE"0402"
SEC"1"
ROOM"PROC_SIDEBAND";
"A"
$PN"1"14;
"B"
$PN"2"10;
%"GND"
"1","(2300,250)","0","mstr_symbols","I99";
;
BODY_TYPE"PLUMBING"
VOLTAGE"0"
CDS_LIB"mstr_symbols"
HDL_POWER"GND"
SIZE"1B";
"A\NAC"10;
END.
